(kicad_pcb
	(version 20260206)
	(generator "pcbnew")
	(generator_version "10.0")
	(general
		(thickness 1.6)
		(legacy_teardrops no)
	)
	(paper "A4")
	(title_block
		(title "03242023_DA0F0TMBIJ0_F0T_Motherboard_J_brd_V01_OCP.brd")
		(comment 1 "Grand Teton / footprints 4716-4720 of 6105")
	)
	(layers
		(0 "F.Cu" signal "TOP")
		(4 "In1.Cu" signal "GND")
		(6 "In2.Cu" signal "IN1")
		(8 "In3.Cu" signal "GND1")
		(10 "In4.Cu" signal "IN2")
		(12 "In5.Cu" signal "GND2")
		(14 "In6.Cu" signal "IN3")
		(16 "In7.Cu" signal "GND3")
		(18 "In8.Cu" signal "VCC")
		(20 "In9.Cu" signal "VCC1")
		(22 "In10.Cu" signal "GND4")
		(24 "In11.Cu" signal "IN4")
		(26 "In12.Cu" signal "GND5")
		(28 "In13.Cu" signal "IN5")
		(30 "In14.Cu" signal "GND6")
		(32 "In15.Cu" signal "IN6")
		(34 "In16.Cu" signal "GND7")
		(2 "B.Cu" signal "BOTTOM")
		(9 "F.Adhes" user "F.Adhesive")
		(11 "B.Adhes" user "B.Adhesive")
		(13 "F.Paste" user "Package Geometry/Pastemask Top")
		(15 "B.Paste" user "Package Geometry/Pastemask Bottom")
		(5 "F.SilkS" user "Ref Des/Silkscreen Top")
		(7 "B.SilkS" user "Ref Des/Silkscreen Bottom")
		(1 "F.Mask" user "Board Geometry/Soldermask Top")
		(3 "B.Mask" user "Board Geometry/Soldermask Bottom")
		(17 "Dwgs.User" user "User.Drawings")
		(19 "Cmts.User" user "User.Comments")
		(21 "Eco1.User" user "User.Eco1")
		(23 "Eco2.User" user "User.Eco2")
		(25 "Edge.Cuts" user "Board Geometry/Outline")
		(27 "Margin" user)
		(31 "F.CrtYd" user "Package Geometry/Place Bound Top")
		(29 "B.CrtYd" user "Package Geometry/Place Bound Bottom")
		(35 "F.Fab" user "Ref Des/Assembly Top")
		(33 "B.Fab" user "Ref Des/Assembly Bottom")
	)
	(footprint ""
		(layer "B.Cu")
		(at 329.240388 -2.156206)
		(property "Reference" "J82"
			(at 4.361942 1.140206 270)
			(unlocked yes)
			(layer "B.SilkS")
			(effects
				(font
					(size 0.7874 0.5842)
					(thickness 0.1524)
				)
				(justify left mirror)
			)
		)
		(property "Value" ""
			(at 0 0 0)
			(layer "B.Fab")
			(effects
				(font
					(size 1.27 1.27)
				)
				(justify mirror)
			)
		)
		(duplicate_pad_numbers_are_jumpers no)
		(fp_line
			(start -1.2192 -2.1082)
			(end -1.2192 2.1082)
			(stroke
				(width 0.1524)
				(type default)
			)
			(layer "B.SilkS")
		)
		(fp_line
			(start -1.2192 2.1082)
			(end 1.2192 2.1082)
			(stroke
				(width 0.1524)
				(type default)
			)
			(layer "B.SilkS")
		)
		(fp_line
			(start 1.2192 -2.1082)
			(end -1.2192 -2.1082)
			(stroke
				(width 0.1524)
				(type default)
			)
			(layer "B.SilkS")
		)
		(fp_line
			(start 1.2192 2.1082)
			(end 1.2192 -2.1082)
			(stroke
				(width 0.1524)
				(type default)
			)
			(layer "B.SilkS")
		)
		(pad "" np_thru_hole circle
			(at -3.4671 -1.27 270)
			(size 1.0414 1.0414)
			(drill 1.0414)
			(layers "*.Cu" "*.Mask")
			(clearance 0.381)
			(thermal_gap 0.381)
		)
		(pad "" np_thru_hole circle
			(at -3.4671 1.27 270)
			(size 1.0414 1.0414)
			(drill 1.0414)
			(layers "*.Cu" "*.Mask")
			(clearance 0.381)
			(thermal_gap 0.381)
		)
		(pad "" np_thru_hole circle
			(at 2.8829 -1.27 270)
			(size 1.0414 1.0414)
			(drill 1.0414)
			(layers "*.Cu" "*.Mask")
			(clearance 0.381)
			(thermal_gap 0.381)
		)
		(pad "" np_thru_hole circle
			(at 2.8829 1.27 270)
			(size 1.0414 1.0414)
			(drill 1.0414)
			(layers "*.Cu" "*.Mask")
			(clearance 0.381)
			(thermal_gap 0.381)
		)
		(pad "1" smd rect
			(at -0.8255 -0.249936 270)
			(size 0.3048 0.508)
			(layers "B.Cu" "B.Mask" "B.Paste")
			(net "DELTA_L_85_10INCH_BOT_DN")
		)
		(pad "2" smd rect
			(at -0.8255 0.249936 270)
			(size 0.3048 0.508)
			(layers "B.Cu" "B.Mask" "B.Paste")
			(net "DELTA_L_85_10INCH_BOT_DP")
		)
		(pad "3" smd circle
			(at 0 0 180)
			(size 0 0)
			(layers "B.Cu" "B.Mask" "B.Paste")
			(net "DELTA_L_GND_1")
		)
		(zone
			(layers "F.Cu" "B.Cu" "In1.Cu" "In2.Cu" "In3.Cu" "In4.Cu" "In5.Cu" "In6.Cu"
				"In7.Cu" "In8.Cu" "In9.Cu" "In10.Cu" "In11.Cu" "In12.Cu" "In13.Cu" "In14.Cu"
				"In15.Cu" "In16.Cu"
			)
			(hatch none 0.5)
			(connect_pads
				(clearance 0)
			)
			(min_thickness 0.25)
			(keepout
				(tracks not_allowed)
				(vias allowed)
				(pads allowed)
				(copperpour not_allowed)
				(footprints allowed)
			)
			(placement
				(enabled no)
				(sheetname "")
			)
			(fill
				(thermal_gap 0.5)
				(thermal_bridge_width 0.5)
				(island_removal_mode 0)
			)
			(polygon
				(pts
					(arc
						(start 326.700388 -3.426206)
						(mid 324.846188 -3.426206)
						(end 326.700388 -3.426206)
					)
				)
			)
		)
		(zone
			(layers "F.Cu" "B.Cu" "In1.Cu" "In2.Cu" "In3.Cu" "In4.Cu" "In5.Cu" "In6.Cu"
				"In7.Cu" "In8.Cu" "In9.Cu" "In10.Cu" "In11.Cu" "In12.Cu" "In13.Cu" "In14.Cu"
				"In15.Cu" "In16.Cu"
			)
			(hatch none 0.5)
			(connect_pads
				(clearance 0)
			)
			(min_thickness 0.25)
			(keepout
				(tracks not_allowed)
				(vias allowed)
				(pads allowed)
				(copperpour not_allowed)
				(footprints allowed)
			)
			(placement
				(enabled no)
				(sheetname "")
			)
			(fill
				(thermal_gap 0.5)
				(thermal_bridge_width 0.5)
				(island_removal_mode 0)
			)
			(polygon
				(pts
					(arc
						(start 326.700388 -0.886206)
						(mid 324.846188 -0.886206)
						(end 326.700388 -0.886206)
					)
				)
			)
		)
		(zone
			(layers "F.Cu" "B.Cu" "In1.Cu" "In2.Cu" "In3.Cu" "In4.Cu" "In5.Cu" "In6.Cu"
				"In7.Cu" "In8.Cu" "In9.Cu" "In10.Cu" "In11.Cu" "In12.Cu" "In13.Cu" "In14.Cu"
				"In15.Cu" "In16.Cu"
			)
			(hatch none 0.5)
			(connect_pads
				(clearance 0)
			)
			(min_thickness 0.25)
			(keepout
				(tracks not_allowed)
				(vias allowed)
				(pads allowed)
				(copperpour not_allowed)
				(footprints allowed)
			)
			(placement
				(enabled no)
				(sheetname "")
			)
			(fill
				(thermal_gap 0.5)
				(thermal_bridge_width 0.5)
				(island_removal_mode 0)
			)
			(polygon
				(pts
					(arc
						(start 333.050388 -3.426206)
						(mid 331.196188 -3.426206)
						(end 333.050388 -3.426206)
					)
				)
			)
		)
		(zone
			(layers "F.Cu" "B.Cu" "In1.Cu" "In2.Cu" "In3.Cu" "In4.Cu" "In5.Cu" "In6.Cu"
				"In7.Cu" "In8.Cu" "In9.Cu" "In10.Cu" "In11.Cu" "In12.Cu" "In13.Cu" "In14.Cu"
				"In15.Cu" "In16.Cu"
			)
			(hatch none 0.5)
			(connect_pads
				(clearance 0)
			)
			(min_thickness 0.25)
			(keepout
				(tracks not_allowed)
				(vias allowed)
				(pads allowed)
				(copperpour not_allowed)
				(footprints allowed)
			)
			(placement
				(enabled no)
				(sheetname "")
			)
			(fill
				(thermal_gap 0.5)
				(thermal_bridge_width 0.5)
				(island_removal_mode 0)
			)
			(polygon
				(pts
					(arc
						(start 333.050388 -0.886206)
						(mid 331.196188 -0.886206)
						(end 333.050388 -0.886206)
					)
				)
			)
		)
		(zone
			(layer "B.Cu")
			(hatch none 0.5)
			(connect_pads
				(clearance 0)
			)
			(min_thickness 0.25)
			(keepout
				(tracks not_allowed)
				(vias allowed)
				(pads allowed)
				(copperpour not_allowed)
				(footprints allowed)
			)
			(placement
				(enabled no)
				(sheetname "")
			)
			(fill
				(thermal_gap 0.5)
				(thermal_bridge_width 0.5)
				(island_removal_mode 0)
			)
			(polygon
				(pts
					(xy 328.122788 -2.704846) (xy 328.122788 -2.609342) (xy 328.719688 -2.609342) (xy 328.719688 -2.202942)
					(xy 328.122788 -2.202942) (xy 328.122788 -2.10947) (xy 328.719688 -2.10947) (xy 328.719688 -1.70307)
					(xy 328.122788 -1.70307) (xy 328.122788 -1.607566) (xy 328.821288 -1.607566) (xy 328.821288 -2.704846)
				)
			)
		)
	)
	(footprint ""
		(layer "B.Cu")
		(at 48.506634 -357.92918 -90)
		(property "Reference" "PR1332"
			(at 0 0 90)
			(layer "B.SilkS")
			(hide yes)
			(effects
				(font
					(size 1.27 1.27)
				)
				(justify mirror)
			)
		)
		(property "Value" ""
			(at 0 0 90)
			(layer "B.Fab")
			(effects
				(font
					(size 1.27 1.27)
				)
				(justify mirror)
			)
		)
		(duplicate_pad_numbers_are_jumpers no)
		(fp_line
			(start -0.7874 0.4064)
			(end 0.7874 0.4064)
			(stroke
				(width 0.1524)
				(type default)
			)
			(layer "B.SilkS")
		)
		(fp_line
			(start 0.7874 0.4064)
			(end 0.7874 -0.4064)
			(stroke
				(width 0.1524)
				(type default)
			)
			(layer "B.SilkS")
		)
		(fp_line
			(start -0.7874 -0.4064)
			(end -0.7874 0.4064)
			(stroke
				(width 0.1524)
				(type default)
			)
			(layer "B.SilkS")
		)
		(fp_line
			(start 0.7874 -0.4064)
			(end -0.7874 -0.4064)
			(stroke
				(width 0.1524)
				(type default)
			)
			(layer "B.SilkS")
		)
		(fp_line
			(start -0.67945 0.3048)
			(end -0.120396 0.3048)
			(stroke
				(width 0.1)
				(type default)
			)
			(layer "B.Fab")
		)
		(fp_line
			(start -0.120396 0.3048)
			(end -0.120396 0.2794)
			(stroke
				(width 0.1)
				(type default)
			)
			(layer "B.Fab")
		)
		(fp_line
			(start 0.12065 0.3048)
			(end 0.67945 0.3048)
			(stroke
				(width 0.1)
				(type default)
			)
			(layer "B.Fab")
		)
		(fp_line
			(start 0.67945 0.3048)
			(end 0.67945 -0.305054)
			(stroke
				(width 0.1)
				(type default)
			)
			(layer "B.Fab")
		)
		(fp_line
			(start -0.120396 0.2794)
			(end 0.12065 0.2794)
			(stroke
				(width 0.1)
				(type default)
			)
			(layer "B.Fab")
		)
		(fp_line
			(start 0.12065 0.2794)
			(end 0.12065 0.3048)
			(stroke
				(width 0.1)
				(type default)
			)
			(layer "B.Fab")
		)
		(fp_line
			(start -0.12065 -0.2794)
			(end -0.12065 -0.3048)
			(stroke
				(width 0.1)
				(type default)
			)
			(layer "B.Fab")
		)
		(fp_line
			(start 0.12065 -0.2794)
			(end -0.12065 -0.2794)
			(stroke
				(width 0.1)
				(type default)
			)
			(layer "B.Fab")
		)
		(fp_line
			(start -0.67945 -0.3048)
			(end -0.67945 0.3048)
			(stroke
				(width 0.1)
				(type default)
			)
			(layer "B.Fab")
		)
		(fp_line
			(start -0.12065 -0.3048)
			(end -0.67945 -0.3048)
			(stroke
				(width 0.1)
				(type default)
			)
			(layer "B.Fab")
		)
		(fp_line
			(start 0.12065 -0.305054)
			(end 0.12065 -0.2794)
			(stroke
				(width 0.1)
				(type default)
			)
			(layer "B.Fab")
		)
		(fp_line
			(start 0.67945 -0.305054)
			(end 0.12065 -0.305054)
			(stroke
				(width 0.1)
				(type default)
			)
			(layer "B.Fab")
		)
		(pad "1" smd circle
			(at 0.40005 0 90)
			(size 0 0)
			(layers "B.Cu" "B.Mask" "B.Paste")
			(net "PVCCFA_EHV_FIVRA_CPU1_VOS2")
		)
		(pad "2" smd circle
			(at -0.40005 0 90)
			(size 0 0)
			(layers "B.Cu" "B.Mask" "B.Paste")
			(net "PVCCFA_EHV_FIVRA_CPU1")
		)
	)
	(footprint ""
		(layer "B.Cu")
		(at 159.279082 -37.323268)
		(property "Reference" "C2316"
			(at 0 0 0)
			(layer "B.SilkS")
			(hide yes)
			(effects
				(font
					(size 1.27 1.27)
				)
				(justify mirror)
			)
		)
		(property "Value" ""
			(at 0 0 0)
			(layer "B.Fab")
			(effects
				(font
					(size 1.27 1.27)
				)
				(justify mirror)
			)
		)
		(duplicate_pad_numbers_are_jumpers no)
		(fp_line
			(start -0.7874 -0.4064)
			(end -0.7874 0.4064)
			(stroke
				(width 0.1524)
				(type default)
			)
			(layer "B.SilkS")
		)
		(fp_line
			(start -0.7874 0.4064)
			(end 0.7874 0.4064)
			(stroke
				(width 0.1524)
				(type default)
			)
			(layer "B.SilkS")
		)
		(fp_line
			(start 0.7874 -0.4064)
			(end -0.7874 -0.4064)
			(stroke
				(width 0.1524)
				(type default)
			)
			(layer "B.SilkS")
		)
		(fp_line
			(start 0.7874 0.4064)
			(end 0.7874 -0.4064)
			(stroke
				(width 0.1524)
				(type default)
			)
			(layer "B.SilkS")
		)
		(fp_line
			(start -0.67945 -0.3048)
			(end -0.67945 0.3048)
			(stroke
				(width 0.1)
				(type default)
			)
			(layer "B.Fab")
		)
		(fp_line
			(start -0.67945 0.3048)
			(end -0.120396 0.3048)
			(stroke
				(width 0.1)
				(type default)
			)
			(layer "B.Fab")
		)
		(fp_line
			(start -0.12065 -0.3048)
			(end -0.67945 -0.3048)
			(stroke
				(width 0.1)
				(type default)
			)
			(layer "B.Fab")
		)
		(fp_line
			(start -0.12065 -0.2794)
			(end -0.12065 -0.3048)
			(stroke
				(width 0.1)
				(type default)
			)
			(layer "B.Fab")
		)
		(fp_line
			(start -0.120396 0.2794)
			(end 0.12065 0.2794)
			(stroke
				(width 0.1)
				(type default)
			)
			(layer "B.Fab")
		)
		(fp_line
			(start -0.120396 0.3048)
			(end -0.120396 0.2794)
			(stroke
				(width 0.1)
				(type default)
			)
			(layer "B.Fab")
		)
		(fp_line
			(start 0.12065 -0.305054)
			(end 0.12065 -0.2794)
			(stroke
				(width 0.1)
				(type default)
			)
			(layer "B.Fab")
		)
		(fp_line
			(start 0.12065 -0.2794)
			(end -0.12065 -0.2794)
			(stroke
				(width 0.1)
				(type default)
			)
			(layer "B.Fab")
		)
		(fp_line
			(start 0.12065 0.2794)
			(end 0.12065 0.3048)
			(stroke
				(width 0.1)
				(type default)
			)
			(layer "B.Fab")
		)
		(fp_line
			(start 0.12065 0.3048)
			(end 0.67945 0.3048)
			(stroke
				(width 0.1)
				(type default)
			)
			(layer "B.Fab")
		)
		(fp_line
			(start 0.67945 -0.305054)
			(end 0.12065 -0.305054)
			(stroke
				(width 0.1)
				(type default)
			)
			(layer "B.Fab")
		)
		(fp_line
			(start 0.67945 0.3048)
			(end 0.67945 -0.305054)
			(stroke
				(width 0.1)
				(type default)
			)
			(layer "B.Fab")
		)
		(pad "1" smd circle
			(at 0.40005 0 180)
			(size 0 0)
			(layers "B.Cu" "B.Mask" "B.Paste")
			(net "P3V3_AUX_USB_HUB_2")
		)
		(pad "2" smd circle
			(at -0.40005 0 180)
			(size 0 0)
			(layers "B.Cu" "B.Mask" "B.Paste")
			(net "GND")
		)
	)
	(footprint ""
		(layer "B.Cu")
		(at 337.903312 -187.996068 90)
		(property "Reference" "R741"
			(at 0 0 90)
			(layer "B.SilkS")
			(hide yes)
			(effects
				(font
					(size 1.27 1.27)
				)
				(justify mirror)
			)
		)
		(property "Value" ""
			(at 0 0 90)
			(layer "B.Fab")
			(effects
				(font
					(size 1.27 1.27)
				)
				(justify mirror)
			)
		)
		(duplicate_pad_numbers_are_jumpers no)
		(fp_line
			(start 0.7874 -0.4064)
			(end -0.7874 -0.4064)
			(stroke
				(width 0.1524)
				(type default)
			)
			(layer "B.SilkS")
		)
		(fp_line
			(start -0.7874 -0.4064)
			(end -0.7874 0.4064)
			(stroke
				(width 0.1524)
				(type default)
			)
			(layer "B.SilkS")
		)
		(fp_line
			(start 0.7874 0.4064)
			(end 0.7874 -0.4064)
			(stroke
				(width 0.1524)
				(type default)
			)
			(layer "B.SilkS")
		)
		(fp_line
			(start -0.7874 0.4064)
			(end 0.7874 0.4064)
			(stroke
				(width 0.1524)
				(type default)
			)
			(layer "B.SilkS")
		)
		(fp_line
			(start 0.67945 -0.305054)
			(end 0.12065 -0.305054)
			(stroke
				(width 0.1)
				(type default)
			)
			(layer "B.Fab")
		)
		(fp_line
			(start 0.12065 -0.305054)
			(end 0.12065 -0.2794)
			(stroke
				(width 0.1)
				(type default)
			)
			(layer "B.Fab")
		)
		(fp_line
			(start -0.12065 -0.3048)
			(end -0.67945 -0.3048)
			(stroke
				(width 0.1)
				(type default)
			)
			(layer "B.Fab")
		)
		(fp_line
			(start -0.67945 -0.3048)
			(end -0.67945 0.3048)
			(stroke
				(width 0.1)
				(type default)
			)
			(layer "B.Fab")
		)
		(fp_line
			(start 0.12065 -0.2794)
			(end -0.12065 -0.2794)
			(stroke
				(width 0.1)
				(type default)
			)
			(layer "B.Fab")
		)
		(fp_line
			(start -0.12065 -0.2794)
			(end -0.12065 -0.3048)
			(stroke
				(width 0.1)
				(type default)
			)
			(layer "B.Fab")
		)
		(fp_line
			(start 0.12065 0.2794)
			(end 0.12065 0.3048)
			(stroke
				(width 0.1)
				(type default)
			)
			(layer "B.Fab")
		)
		(fp_line
			(start -0.120396 0.2794)
			(end 0.12065 0.2794)
			(stroke
				(width 0.1)
				(type default)
			)
			(layer "B.Fab")
		)
		(fp_line
			(start 0.67945 0.3048)
			(end 0.67945 -0.305054)
			(stroke
				(width 0.1)
				(type default)
			)
			(layer "B.Fab")
		)
		(fp_line
			(start 0.12065 0.3048)
			(end 0.67945 0.3048)
			(stroke
				(width 0.1)
				(type default)
			)
			(layer "B.Fab")
		)
		(fp_line
			(start -0.120396 0.3048)
			(end -0.120396 0.2794)
			(stroke
				(width 0.1)
				(type default)
			)
			(layer "B.Fab")
		)
		(fp_line
			(start -0.67945 0.3048)
			(end -0.120396 0.3048)
			(stroke
				(width 0.1)
				(type default)
			)
			(layer "B.Fab")
		)
		(pad "1" smd circle
			(at 0.40005 0 270)
			(size 0 0)
			(layers "B.Cu" "B.Mask" "B.Paste")
			(net "PVNN_TERM_CPU0")
		)
		(pad "2" smd circle
			(at -0.40005 0 270)
			(size 0 0)
			(layers "B.Cu" "B.Mask" "B.Paste")
			(net "JTAG_MUX_CPU0_GTL_TDI")
		)
	)
	(footprint ""
		(layer "B.Cu")
		(at 182.68188 -102.707948)
		(property "Reference" "C1941"
			(at 0 0 0)
			(layer "B.SilkS")
			(hide yes)
			(effects
				(font
					(size 1.27 1.27)
				)
				(justify mirror)
			)
		)
		(property "Value" ""
			(at 0 0 0)
			(layer "B.Fab")
			(effects
				(font
					(size 1.27 1.27)
				)
				(justify mirror)
			)
		)
		(duplicate_pad_numbers_are_jumpers no)
		(fp_line
			(start -0.7874 -0.4064)
			(end -0.7874 0.4064)
			(stroke
				(width 0.1524)
				(type default)
			)
			(layer "B.SilkS")
		)
		(fp_line
			(start -0.7874 0.4064)
			(end 0.7874 0.4064)
			(stroke
				(width 0.1524)
				(type default)
			)
			(layer "B.SilkS")
		)
		(fp_line
			(start 0.7874 -0.4064)
			(end -0.7874 -0.4064)
			(stroke
				(width 0.1524)
				(type default)
			)
			(layer "B.SilkS")
		)
		(fp_line
			(start 0.7874 0.4064)
			(end 0.7874 -0.4064)
			(stroke
				(width 0.1524)
				(type default)
			)
			(layer "B.SilkS")
		)
		(fp_line
			(start -0.67945 -0.3048)
			(end -0.67945 0.3048)
			(stroke
				(width 0.1)
				(type default)
			)
			(layer "B.Fab")
		)
		(fp_line
			(start -0.67945 0.3048)
			(end -0.120396 0.3048)
			(stroke
				(width 0.1)
				(type default)
			)
			(layer "B.Fab")
		)
		(fp_line
			(start -0.12065 -0.3048)
			(end -0.67945 -0.3048)
			(stroke
				(width 0.1)
				(type default)
			)
			(layer "B.Fab")
		)
		(fp_line
			(start -0.12065 -0.2794)
			(end -0.12065 -0.3048)
			(stroke
				(width 0.1)
				(type default)
			)
			(layer "B.Fab")
		)
		(fp_line
			(start -0.120396 0.2794)
			(end 0.12065 0.2794)
			(stroke
				(width 0.1)
				(type default)
			)
			(layer "B.Fab")
		)
		(fp_line
			(start -0.120396 0.3048)
			(end -0.120396 0.2794)
			(stroke
				(width 0.1)
				(type default)
			)
			(layer "B.Fab")
		)
		(fp_line
			(start 0.12065 -0.305054)
			(end 0.12065 -0.2794)
			(stroke
				(width 0.1)
				(type default)
			)
			(layer "B.Fab")
		)
		(fp_line
			(start 0.12065 -0.2794)
			(end -0.12065 -0.2794)
			(stroke
				(width 0.1)
				(type default)
			)
			(layer "B.Fab")
		)
		(fp_line
			(start 0.12065 0.2794)
			(end 0.12065 0.3048)
			(stroke
				(width 0.1)
				(type default)
			)
			(layer "B.Fab")
		)
		(fp_line
			(start 0.12065 0.3048)
			(end 0.67945 0.3048)
			(stroke
				(width 0.1)
				(type default)
			)
			(layer "B.Fab")
		)
		(fp_line
			(start 0.67945 -0.305054)
			(end 0.12065 -0.305054)
			(stroke
				(width 0.1)
				(type default)
			)
			(layer "B.Fab")
		)
		(fp_line
			(start 0.67945 0.3048)
			(end 0.67945 -0.305054)
			(stroke
				(width 0.1)
				(type default)
			)
			(layer "B.Fab")
		)
		(pad "1" smd circle
			(at 0.40005 0 180)
			(size 0 0)
			(layers "B.Cu" "B.Mask" "B.Paste")
			(net "P3V3_AUX_FPGA_VCCIO3")
		)
		(pad "2" smd circle
			(at -0.40005 0 180)
			(size 0 0)
			(layers "B.Cu" "B.Mask" "B.Paste")
			(net "GND")
		)
	)
)
